M48
;Layer_Color=9474304
;FILE_FORMAT=2:5
INCH,LZ
;TYPE=PLATED
T1F00S00C0.01200
%
T01
X0009467Y0020459
X0019467
X0029467
X0039467
X0049467
Y0030459
Y0040459
X0039467
Y0050459
X0029467
Y0040459
Y0030459
X0039467
Y0010459
X0049467
X0029467
X0019467Y0030459
Y0040459
Y0050459
X0009467
Y0040459
Y0030459
X00566Y0049
X0065561Y0053239
X00628Y00567
X0069467Y0050459
Y0040459
X0089467
Y0050459
Y0030459
X0099467Y0020459
X0109467
X01087Y0029
X0117025
X012535
X0133675
X0142
X01419Y00373
X0133575
X012525
X0116925
X01086
X01087Y00457
X0117025
X012535
X0133675
X0142
Y00541
X0133675
X012535
X0117025
X01087
X0119467Y0020459
X0129467
X0139467
X0149467
X0159467
X0169467
X0179467
X0189467Y0030459
X0199467
X0207517Y0032817
Y0043428
X0189467Y0040459
Y0050459
X01939Y0056
X0179467Y0050459
Y0040459
X0169467Y0050459
Y0030459
X0159467
Y0040459
X0189467Y0010459
X0089467
X0079467
Y0020459
X0069467
X0059467Y0010459
X0229467
X0239467
Y0020459
X0249467
X0259467
Y0030459
Y0040459
Y0050459
X0239467
X02154Y00472
X02221Y00405
X0259467Y0010459
Y0060459
Y0070459
Y0080459
Y0090459
Y0100459
Y0110459
Y0120459
X0239467
Y0110459
Y0100459
X0249467
Y0090459
X0239467
X0229467
Y0100459
Y0110459
Y0120459
X0219467
Y0110459
Y0100459
Y0090459
X02174Y008
X02172Y00721
X0229467Y0070459
Y0080459
Y0060459
X02251Y00612
X0239467Y0060459
X0209467
X02086Y00721
X01983Y00658
X01872Y00657
X0189467Y0060459
X0179467
X0169467
Y0080459
X0159467
Y0090459
X0179467
X0189467
Y0080459
X0199467
X0209467Y0100459
Y0110459
Y0120459
X0199467
Y0110459
X0189467Y0120459
X0179467
X0169467
X0159467
X0149467
X0139467
X0129467
X0119467
Y0110459
X01212Y01067
Y0102269
X01377Y01042
Y01112
X0133575Y00788
X01419
Y00704
Y00621
X0133575
Y00704
X012525
Y00621
X0116925
Y00704
X01086
Y00621
Y00788
X0116925
X012525
X0087968Y0080005
X0083568
X0079232Y0080753
X0075868
X0071486Y0080358
X0067086
X0062686
X0058286
X005696Y0075547
X006136
X006576
X007016
X00758Y00744
X0080035Y0074573
X0084391Y0075195
X0088791
X0089467Y0090459
Y0100459
Y0110459
X0099467
Y0120459
X0109467
X0089467
X0079467
Y0110459
Y0100459
Y0090459
X0069467
Y0100459
Y0110459
Y0120459
X0059467
Y0110459
Y0100459
Y0090459
X00695Y00663
X00679Y0059
X0159467Y0070459
X00548Y00633
X0053886Y0080358
X0049486
X0045088Y0080484
X0040689Y0080358
X0036289
X0031889
X0027503Y0080696
X0027335Y0074913
X0031689Y0075547
X0036089
X0040202Y0073983
X0039467Y0070459
Y0060459
X0029467
Y0070459
X0023616Y0072562
X0019368Y0073711
X0017342Y0077617
X0018874Y0081741
X0023955Y0083298
X0009467Y0080459
Y0090459
Y0100459
X0019467
X0029467
X0039467
X0049467
Y0110459
Y0120459
X0039467
Y0110459
X0029467
Y0120459
X0019467
Y0110459
X0039467Y0090459
X0049467
X00476Y00752
X0019467Y0060459
X0009467
Y0070459
M30
